(kicad_pcb
	(version 20260206)
	(generator "pcbnew")
	(generator_version "10.0")
	(general
		(thickness 1.6)
		(legacy_teardrops no)
	)
	(paper "A4")
	(title_block
		(title "v1-chassis-manager — T6M_CM_d_v01_1031_1645.brd")
		(comment 1 "Open CloudServer (Microsoft) / footprints 694-702 of 2512")
	)
	(layers
		(0 "F.Cu" signal "TOP")
		(4 "In1.Cu" signal "GND1")
		(6 "In2.Cu" signal "IN1")
		(8 "In3.Cu" signal "VCC1")
		(10 "In4.Cu" signal "VCC2")
		(12 "In5.Cu" signal "GND2")
		(14 "In6.Cu" signal "IN2")
		(16 "In7.Cu" signal "IN3")
		(18 "In8.Cu" signal "GND3")
		(2 "B.Cu" signal "BOTTOM")
		(9 "F.Adhes" user "F.Adhesive")
		(11 "B.Adhes" user "B.Adhesive")
		(13 "F.Paste" user "Package Geometry/Pastemask Top")
		(15 "B.Paste" user "Package Geometry/Pastemask Bottom")
		(5 "F.SilkS" user "Ref Des/Silkscreen Top")
		(7 "B.SilkS" user "Ref Des/Silkscreen Bottom")
		(1 "F.Mask" user "Board Geometry/Soldermask Top")
		(3 "B.Mask" user "Board Geometry/Soldermask Bottom")
		(17 "Dwgs.User" user "User.Drawings")
		(19 "Cmts.User" user "User.Comments")
		(21 "Eco1.User" user "User.Eco1")
		(23 "Eco2.User" user "User.Eco2")
		(25 "Edge.Cuts" user "Board Geometry/Outline")
		(27 "Margin" user)
		(31 "F.CrtYd" user "Package Geometry/Place Bound Top")
		(29 "B.CrtYd" user "Package Geometry/Place Bound Bottom")
		(35 "F.Fab" user "Ref Des/Assembly Top")
		(33 "B.Fab" user "Ref Des/Assembly Bottom")
	)
	(footprint ""
		(layer "F.Cu")
		(at 90.81262 -178.594512 180)
		(property "Reference" "R810"
			(at -85.97392 -76.296012 0)
			(unlocked yes)
			(layer "F.SilkS")
			(effects
				(font
					(size 0.7874 0.5842)
					(thickness 0.1524)
				)
				(justify left)
			)
		)
		(property "Value" ""
			(at 0 0 180)
			(layer "F.Fab")
			(effects
				(font
					(size 1.27 1.27)
				)
			)
		)
		(duplicate_pad_numbers_are_jumpers no)
		(fp_line
			(start 0.7874 0.4064)
			(end -0.7874 0.4064)
			(stroke
				(width 0.1524)
				(type default)
			)
			(layer "F.SilkS")
		)
		(fp_line
			(start 0.7874 -0.4064)
			(end 0.7874 0.4064)
			(stroke
				(width 0.1524)
				(type default)
			)
			(layer "F.SilkS")
		)
		(fp_line
			(start -0.7874 0.4064)
			(end -0.7874 -0.4064)
			(stroke
				(width 0.1524)
				(type default)
			)
			(layer "F.SilkS")
		)
		(fp_line
			(start -0.7874 -0.4064)
			(end 0.7874 -0.4064)
			(stroke
				(width 0.1524)
				(type default)
			)
			(layer "F.SilkS")
		)
		(fp_poly
			(pts
				(xy -0.508 0.2794) (xy -0.508 0.2286) (xy -0.635 0.2286) (xy -0.635 -0.254) (xy -0.5334 -0.254)
				(xy -0.5334 -0.2794) (xy 0.5334 -0.2794) (xy 0.5334 -0.254) (xy 0.635 -0.254) (xy 0.635 0.254) (xy 0.5334 0.254)
				(xy 0.5334 0.2794)
			)
			(stroke
				(width 0)
				(type default)
			)
			(fill no)
			(layer "F.CrtYd")
		)
		(pad "1" smd rect
			(at 0.40005 0 180)
			(size 0.4572 0.508)
			(layers "F.Cu" "F.Mask" "F.Paste")
			(net "CPLD_UART_RI_P4_N")
		)
		(pad "2" smd rect
			(at -0.40005 0 180)
			(size 0.4572 0.508)
			(layers "F.Cu" "F.Mask" "F.Paste")
			(net "GND")
		)
	)
	(footprint ""
		(layer "F.Cu")
		(at 151.309578 -57.249822 -90)
		(property "Reference" "R518"
			(at -14.50213 -26.0858 90)
			(unlocked yes)
			(layer "F.SilkS")
			(effects
				(font
					(size 0.7874 0.5842)
					(thickness 0.1524)
				)
				(justify left)
			)
		)
		(property "Value" ""
			(at 0 0 270)
			(layer "F.Fab")
			(effects
				(font
					(size 1.27 1.27)
				)
			)
		)
		(duplicate_pad_numbers_are_jumpers no)
		(fp_line
			(start -0.7874 0.4064)
			(end -0.7874 -0.4064)
			(stroke
				(width 0.1524)
				(type default)
			)
			(layer "F.SilkS")
		)
		(fp_line
			(start 0.7874 0.4064)
			(end -0.7874 0.4064)
			(stroke
				(width 0.1524)
				(type default)
			)
			(layer "F.SilkS")
		)
		(fp_line
			(start -0.7874 -0.4064)
			(end 0.7874 -0.4064)
			(stroke
				(width 0.1524)
				(type default)
			)
			(layer "F.SilkS")
		)
		(fp_line
			(start 0.7874 -0.4064)
			(end 0.7874 0.4064)
			(stroke
				(width 0.1524)
				(type default)
			)
			(layer "F.SilkS")
		)
		(fp_poly
			(pts
				(xy -0.508 0.2794) (xy -0.508 0.2286) (xy -0.635 0.2286) (xy -0.635 -0.254) (xy -0.5334 -0.254)
				(xy -0.5334 -0.2794) (xy 0.5334 -0.2794) (xy 0.5334 -0.254) (xy 0.635 -0.254) (xy 0.635 0.254) (xy 0.5334 0.254)
				(xy 0.5334 0.2794)
			)
			(stroke
				(width 0)
				(type default)
			)
			(fill no)
			(layer "F.CrtYd")
		)
		(pad "1" smd rect
			(at 0.40005 0 270)
			(size 0.4572 0.508)
			(layers "F.Cu" "F.Mask" "F.Paste")
			(net "GND")
		)
		(pad "2" smd rect
			(at -0.40005 0 270)
			(size 0.4572 0.508)
			(layers "F.Cu" "F.Mask" "F.Paste")
			(net "SATA_NODE1_GPIO5")
		)
	)
	(footprint ""
		(layer "F.Cu")
		(at 12.95908 -119.88419)
		(property "Reference" "PR22"
			(at -5.507228 -1.311402 0)
			(unlocked yes)
			(layer "F.SilkS")
			(effects
				(font
					(size 0.7874 0.5842)
					(thickness 0.1524)
				)
				(justify left)
			)
		)
		(property "Value" ""
			(at 0 0 0)
			(layer "F.Fab")
			(effects
				(font
					(size 1.27 1.27)
				)
			)
		)
		(duplicate_pad_numbers_are_jumpers no)
		(fp_line
			(start -2.2098 -0.9398)
			(end 2.2098 -0.9398)
			(stroke
				(width 0.1524)
				(type default)
			)
			(layer "F.SilkS")
		)
		(fp_line
			(start -2.2098 0.9398)
			(end -2.2098 -0.9398)
			(stroke
				(width 0.1524)
				(type default)
			)
			(layer "F.SilkS")
		)
		(fp_line
			(start 2.2098 -0.9398)
			(end 2.2098 0.9398)
			(stroke
				(width 0.1524)
				(type default)
			)
			(layer "F.SilkS")
		)
		(fp_line
			(start 2.2098 0.9398)
			(end -2.2098 0.9398)
			(stroke
				(width 0.1524)
				(type default)
			)
			(layer "F.SilkS")
		)
		(fp_poly
			(pts
				(xy 2.0574 0.8382) (xy 2.0574 -0.8382) (xy 2.0574 -0.9398) (xy -2.0574 -0.9398) (xy -2.0574 -0.8382)
				(xy -2.0574 0.8382) (xy -2.0574 0.9398) (xy 2.0574 0.9398)
			)
			(stroke
				(width 0)
				(type default)
			)
			(fill no)
			(layer "F.CrtYd")
		)
		(pad "1" smd rect
			(at 1.4732 0)
			(size 1.1684 1.5748)
			(layers "F.Cu" "F.Mask" "F.Paste")
			(net "SW_P1V05_NODE1_VIN_FLT")
		)
		(pad "2" smd rect
			(at -1.4732 0)
			(size 1.1684 1.5748)
			(layers "F.Cu" "F.Mask" "F.Paste")
			(net "P12V_AUX")
		)
	)
	(footprint ""
		(layer "F.Cu")
		(at 144.51076 -185.205624 -90)
		(property "Reference" "R996"
			(at -4.768088 0.535432 90)
			(unlocked yes)
			(layer "F.SilkS")
			(effects
				(font
					(size 0.7874 0.5842)
					(thickness 0.1524)
				)
				(justify left)
			)
		)
		(property "Value" ""
			(at 0 0 270)
			(layer "F.Fab")
			(effects
				(font
					(size 1.27 1.27)
				)
			)
		)
		(duplicate_pad_numbers_are_jumpers no)
		(fp_line
			(start -0.7874 0.4064)
			(end -0.7874 -0.4064)
			(stroke
				(width 0.1524)
				(type default)
			)
			(layer "F.SilkS")
		)
		(fp_line
			(start 0.7874 0.4064)
			(end -0.7874 0.4064)
			(stroke
				(width 0.1524)
				(type default)
			)
			(layer "F.SilkS")
		)
		(fp_line
			(start -0.7874 -0.4064)
			(end 0.7874 -0.4064)
			(stroke
				(width 0.1524)
				(type default)
			)
			(layer "F.SilkS")
		)
		(fp_line
			(start 0.7874 -0.4064)
			(end 0.7874 0.4064)
			(stroke
				(width 0.1524)
				(type default)
			)
			(layer "F.SilkS")
		)
		(fp_poly
			(pts
				(xy -0.508 0.2794) (xy -0.508 0.2286) (xy -0.635 0.2286) (xy -0.635 -0.254) (xy -0.5334 -0.254)
				(xy -0.5334 -0.2794) (xy 0.5334 -0.2794) (xy 0.5334 -0.254) (xy 0.635 -0.254) (xy 0.635 0.254) (xy 0.5334 0.254)
				(xy 0.5334 0.2794)
			)
			(stroke
				(width 0)
				(type default)
			)
			(fill no)
			(layer "F.CrtYd")
		)
		(pad "1" smd rect
			(at 0.40005 0 270)
			(size 0.4572 0.508)
			(layers "F.Cu" "F.Mask" "F.Paste")
			(net "UART_T12_NODE3_TXD")
		)
		(pad "2" smd rect
			(at -0.40005 0 270)
			(size 0.4572 0.508)
			(layers "F.Cu" "F.Mask" "F.Paste")
			(net "UART_T12_NODE3_TXD_R")
		)
	)
	(footprint ""
		(layer "F.Cu")
		(at 126.60122 -174.667926)
		(property "Reference" "C900"
			(at -0.903732 -1.136396 0)
			(unlocked yes)
			(layer "F.SilkS")
			(effects
				(font
					(size 0.7874 0.5842)
					(thickness 0.1524)
				)
				(justify left)
			)
		)
		(property "Value" ""
			(at 0 0 0)
			(layer "F.Fab")
			(effects
				(font
					(size 1.27 1.27)
				)
			)
		)
		(duplicate_pad_numbers_are_jumpers no)
		(fp_line
			(start -0.7874 -0.4064)
			(end 0.7874 -0.4064)
			(stroke
				(width 0.1524)
				(type default)
			)
			(layer "F.SilkS")
		)
		(fp_line
			(start -0.7874 0.4064)
			(end -0.7874 -0.4064)
			(stroke
				(width 0.1524)
				(type default)
			)
			(layer "F.SilkS")
		)
		(fp_line
			(start 0 0.381)
			(end 0 -0.381)
			(stroke
				(width 0.1524)
				(type default)
			)
			(layer "F.SilkS")
		)
		(fp_line
			(start 0.7874 -0.4064)
			(end 0.7874 0.4064)
			(stroke
				(width 0.1524)
				(type default)
			)
			(layer "F.SilkS")
		)
		(fp_line
			(start 0.7874 0.4064)
			(end -0.7874 0.4064)
			(stroke
				(width 0.1524)
				(type default)
			)
			(layer "F.SilkS")
		)
		(fp_poly
			(pts
				(xy -0.5334 0.254) (xy -0.635 0.254) (xy -0.635 0.2286) (xy -0.635 -0.254) (xy -0.5334 -0.254) (xy -0.5334 -0.2794)
				(xy 0.5334 -0.2794) (xy 0.5334 -0.254) (xy 0.635 -0.254) (xy 0.635 0.254) (xy 0.5334 0.254) (xy 0.5334 0.2794)
				(xy -0.508 0.2794) (xy -0.5334 0.2794)
			)
			(stroke
				(width 0)
				(type default)
			)
			(fill no)
			(layer "F.CrtYd")
		)
		(pad "1" smd rect
			(at 0.40005 0)
			(size 0.4572 0.508)
			(layers "F.Cu" "F.Mask" "F.Paste")
			(net "P3V3_NODE1")
		)
		(pad "2" smd rect
			(at -0.40005 0)
			(size 0.4572 0.508)
			(layers "F.Cu" "F.Mask" "F.Paste")
			(net "GND")
		)
	)
	(footprint ""
		(layer "F.Cu")
		(at 33.212786 -185.3565)
		(property "Reference" "C778"
			(at -5.207254 -5.227066 0)
			(unlocked yes)
			(layer "F.SilkS")
			(effects
				(font
					(size 0.7874 0.5842)
					(thickness 0.1524)
				)
				(justify left)
			)
		)
		(property "Value" ""
			(at 0 0 0)
			(layer "F.Fab")
			(effects
				(font
					(size 1.27 1.27)
				)
			)
		)
		(duplicate_pad_numbers_are_jumpers no)
		(fp_line
			(start -0.7874 -0.4064)
			(end 0.7874 -0.4064)
			(stroke
				(width 0.1524)
				(type default)
			)
			(layer "F.SilkS")
		)
		(fp_line
			(start -0.7874 0.4064)
			(end -0.7874 -0.4064)
			(stroke
				(width 0.1524)
				(type default)
			)
			(layer "F.SilkS")
		)
		(fp_line
			(start 0 0.381)
			(end 0 -0.381)
			(stroke
				(width 0.1524)
				(type default)
			)
			(layer "F.SilkS")
		)
		(fp_line
			(start 0.7874 -0.4064)
			(end 0.7874 0.4064)
			(stroke
				(width 0.1524)
				(type default)
			)
			(layer "F.SilkS")
		)
		(fp_line
			(start 0.7874 0.4064)
			(end -0.7874 0.4064)
			(stroke
				(width 0.1524)
				(type default)
			)
			(layer "F.SilkS")
		)
		(fp_poly
			(pts
				(xy -0.5334 0.254) (xy -0.635 0.254) (xy -0.635 0.2286) (xy -0.635 -0.254) (xy -0.5334 -0.254) (xy -0.5334 -0.2794)
				(xy 0.5334 -0.2794) (xy 0.5334 -0.254) (xy 0.635 -0.254) (xy 0.635 0.254) (xy 0.5334 0.254) (xy 0.5334 0.2794)
				(xy -0.508 0.2794) (xy -0.5334 0.2794)
			)
			(stroke
				(width 0)
				(type default)
			)
			(fill no)
			(layer "F.CrtYd")
		)
		(pad "1" smd rect
			(at 0.40005 0)
			(size 0.4572 0.508)
			(layers "F.Cu" "F.Mask" "F.Paste")
			(net "P12V_AUX_EN")
		)
		(pad "2" smd rect
			(at -0.40005 0)
			(size 0.4572 0.508)
			(layers "F.Cu" "F.Mask" "F.Paste")
			(net "AGND_HSC_NODE1")
		)
	)
	(footprint ""
		(layer "F.Cu")
		(at 162.924998 -144.46123 180)
		(property "Reference" "C437"
			(at 0.840994 0.993648 0)
			(unlocked yes)
			(layer "F.SilkS")
			(effects
				(font
					(size 0.7874 0.5842)
					(thickness 0.1524)
				)
				(justify left)
			)
		)
		(property "Value" ""
			(at 0 0 180)
			(layer "F.Fab")
			(effects
				(font
					(size 1.27 1.27)
				)
			)
		)
		(duplicate_pad_numbers_are_jumpers no)
		(fp_line
			(start 0.7874 0.4064)
			(end -0.7874 0.4064)
			(stroke
				(width 0.1524)
				(type default)
			)
			(layer "F.SilkS")
		)
		(fp_line
			(start 0.7874 -0.4064)
			(end 0.7874 0.4064)
			(stroke
				(width 0.1524)
				(type default)
			)
			(layer "F.SilkS")
		)
		(fp_line
			(start 0 0.381)
			(end 0 -0.381)
			(stroke
				(width 0.1524)
				(type default)
			)
			(layer "F.SilkS")
		)
		(fp_line
			(start -0.7874 0.4064)
			(end -0.7874 -0.4064)
			(stroke
				(width 0.1524)
				(type default)
			)
			(layer "F.SilkS")
		)
		(fp_line
			(start -0.7874 -0.4064)
			(end 0.7874 -0.4064)
			(stroke
				(width 0.1524)
				(type default)
			)
			(layer "F.SilkS")
		)
		(fp_poly
			(pts
				(xy -0.5334 0.254) (xy -0.635 0.254) (xy -0.635 0.2286) (xy -0.635 -0.254) (xy -0.5334 -0.254) (xy -0.5334 -0.2794)
				(xy 0.5334 -0.2794) (xy 0.5334 -0.254) (xy 0.635 -0.254) (xy 0.635 0.254) (xy 0.5334 0.254) (xy 0.5334 0.2794)
				(xy -0.508 0.2794) (xy -0.5334 0.2794)
			)
			(stroke
				(width 0)
				(type default)
			)
			(fill no)
			(layer "F.CrtYd")
		)
		(pad "1" smd rect
			(at 0.40005 0 180)
			(size 0.4572 0.508)
			(layers "F.Cu" "F.Mask" "F.Paste")
			(net "LAN2_XTAL_IN")
		)
		(pad "2" smd rect
			(at -0.40005 0 180)
			(size 0.4572 0.508)
			(layers "F.Cu" "F.Mask" "F.Paste")
			(net "GND")
		)
	)
	(footprint ""
		(layer "F.Cu")
		(at 107.29976 -188.126624 -90)
		(property "Reference" "R933"
			(at -5.151882 -0.78486 90)
			(unlocked yes)
			(layer "F.SilkS")
			(effects
				(font
					(size 0.7874 0.5842)
					(thickness 0.1524)
				)
				(justify left)
			)
		)
		(property "Value" ""
			(at 0 0 270)
			(layer "F.Fab")
			(effects
				(font
					(size 1.27 1.27)
				)
			)
		)
		(duplicate_pad_numbers_are_jumpers no)
		(fp_line
			(start -0.7874 0.4064)
			(end -0.7874 -0.4064)
			(stroke
				(width 0.1524)
				(type default)
			)
			(layer "F.SilkS")
		)
		(fp_line
			(start 0.7874 0.4064)
			(end -0.7874 0.4064)
			(stroke
				(width 0.1524)
				(type default)
			)
			(layer "F.SilkS")
		)
		(fp_line
			(start -0.7874 -0.4064)
			(end 0.7874 -0.4064)
			(stroke
				(width 0.1524)
				(type default)
			)
			(layer "F.SilkS")
		)
		(fp_line
			(start 0.7874 -0.4064)
			(end 0.7874 0.4064)
			(stroke
				(width 0.1524)
				(type default)
			)
			(layer "F.SilkS")
		)
		(fp_poly
			(pts
				(xy -0.508 0.2794) (xy -0.508 0.2286) (xy -0.635 0.2286) (xy -0.635 -0.254) (xy -0.5334 -0.254)
				(xy -0.5334 -0.2794) (xy 0.5334 -0.2794) (xy 0.5334 -0.254) (xy 0.635 -0.254) (xy 0.635 0.254) (xy 0.5334 0.254)
				(xy 0.5334 0.2794)
			)
			(stroke
				(width 0)
				(type default)
			)
			(fill no)
			(layer "F.CrtYd")
		)
		(pad "1" smd rect
			(at 0.40005 0 270)
			(size 0.4572 0.508)
			(layers "F.Cu" "F.Mask" "F.Paste")
			(net "UART_T6_NODE1_RXD")
		)
		(pad "2" smd rect
			(at -0.40005 0 270)
			(size 0.4572 0.508)
			(layers "F.Cu" "F.Mask" "F.Paste")
			(net "UART_T6_NODE1_RXD_R")
		)
	)
	(footprint ""
		(layer "F.Cu")
		(at 94.451932 -177.354992)
		(property "Reference" "R753"
			(at 86.67369 74.174096 0)
			(unlocked yes)
			(layer "F.SilkS")
			(effects
				(font
					(size 0.7874 0.5842)
					(thickness 0.1524)
				)
				(justify left)
			)
		)
		(property "Value" ""
			(at 0 0 0)
			(layer "F.Fab")
			(effects
				(font
					(size 1.27 1.27)
				)
			)
		)
		(duplicate_pad_numbers_are_jumpers no)
		(fp_line
			(start -0.7874 -0.4064)
			(end 0.7874 -0.4064)
			(stroke
				(width 0.1524)
				(type default)
			)
			(layer "F.SilkS")
		)
		(fp_line
			(start -0.7874 0.4064)
			(end -0.7874 -0.4064)
			(stroke
				(width 0.1524)
				(type default)
			)
			(layer "F.SilkS")
		)
		(fp_line
			(start 0.7874 -0.4064)
			(end 0.7874 0.4064)
			(stroke
				(width 0.1524)
				(type default)
			)
			(layer "F.SilkS")
		)
		(fp_line
			(start 0.7874 0.4064)
			(end -0.7874 0.4064)
			(stroke
				(width 0.1524)
				(type default)
			)
			(layer "F.SilkS")
		)
		(fp_poly
			(pts
				(xy -0.508 0.2794) (xy -0.508 0.2286) (xy -0.635 0.2286) (xy -0.635 -0.254) (xy -0.5334 -0.254)
				(xy -0.5334 -0.2794) (xy 0.5334 -0.2794) (xy 0.5334 -0.254) (xy 0.635 -0.254) (xy 0.635 0.254) (xy 0.5334 0.254)
				(xy 0.5334 0.2794)
			)
			(stroke
				(width 0)
				(type default)
			)
			(fill no)
			(layer "F.CrtYd")
		)
		(pad "1" smd rect
			(at 0.40005 0)
			(size 0.4572 0.508)
			(layers "F.Cu" "F.Mask" "F.Paste")
			(net "N21698939")
		)
		(pad "2" smd rect
			(at -0.40005 0)
			(size 0.4572 0.508)
			(layers "F.Cu" "F.Mask" "F.Paste")
			(net "GND")
		)
	)
)
